(kicad_sch
	(version 20250114)
	(generator "eeschema")
	(generator_version "9.0")
	(paper "A3")
	(title_block
		(title "LPDDR4 testbed")
		(date "2024-03-26")
		(rev "1.2.2")
	)
	(text "test-board:IO_V12"
		(exclude_from_sim no)
		(at 157.48 131.445 0)
		(effects
			(font
				(size 1.27 1.27)
			)
			(justify left bottom)
		)
	)
	(text "test-board:IO_U12"
		(exclude_from_sim no)
		(at 157.48 128.905 0)
		(effects
			(font
				(size 1.27 1.27)
			)
			(justify left bottom)
		)
	)
	(text "test-board:IO_U12"
		(exclude_from_sim no)
		(at 158.75 182.245 0)
		(effects
			(font
				(size 1.27 1.27)
			)
			(justify left bottom)
		)
	)
	(text "1V8_SYS"
		(exclude_from_sim no)
		(at 176.53 67.31 0)
		(effects
			(font
				(size 2.0066 2.0066)
				(thickness 0.4013)
				(bold yes)
			)
			(justify left bottom)
		)
	)
	(text "test-board:IO_V12"
		(exclude_from_sim no)
		(at 158.75 184.785 0)
		(effects
			(font
				(size 1.27 1.27)
			)
			(justify left bottom)
		)
	)
	(junction
		(at 196.85 184.15)
		(diameter 0)
		(color 0 0 0 0)
	)
	(junction
		(at 199.39 123.19)
		(diameter 0)
		(color 0 0 0 0)
	)
	(junction
		(at 190.5 86.36)
		(diameter 0)
		(color 0 0 0 0)
	)
	(junction
		(at 232.41 181.61)
		(diameter 0)
		(color 0 0 0 0)
	)
	(junction
		(at 234.315 86.36)
		(diameter 0)
		(color 0 0 0 0)
	)
	(junction
		(at 182.88 74.93)
		(diameter 0)
		(color 0 0 0 0)
	)
	(junction
		(at 240.665 169.545)
		(diameter 0)
		(color 0 0 0 0)
	)
	(junction
		(at 199.39 138.43)
		(diameter 0)
		(color 0 0 0 0)
	)
	(junction
		(at 229.235 74.93)
		(diameter 0)
		(color 0 0 0 0)
	)
	(junction
		(at 234.315 74.93)
		(diameter 0)
		(color 0 0 0 0)
	)
	(junction
		(at 196.85 186.69)
		(diameter 0)
		(color 0 0 0 0)
	)
	(junction
		(at 240.665 181.61)
		(diameter 0)
		(color 0 0 0 0)
	)
	(junction
		(at 196.85 169.545)
		(diameter 0)
		(color 0 0 0 0)
	)
	(junction
		(at 189.23 181.61)
		(diameter 0)
		(color 0 0 0 0)
	)
	(junction
		(at 207.645 86.36)
		(diameter 0)
		(color 0 0 0 0)
	)
	(no_connect
		(at 232.41 138.43)
	)
	(no_connect
		(at 210.82 135.89)
	)
	(no_connect
		(at 232.41 140.97)
	)
	(wire
		(pts
			(xy 229.235 74.93) (xy 234.315 74.93)
		)
		(stroke
			(width 0)
			(type default)
		)
	)
	(wire
		(pts
			(xy 259.08 142.24) (xy 259.08 153.67)
		)
		(stroke
			(width 0)
			(type default)
		)
	)
	(wire
		(pts
			(xy 182.88 123.19) (xy 199.39 123.19)
		)
		(stroke
			(width 0)
			(type default)
		)
	)
	(wire
		(pts
			(xy 207.645 86.995) (xy 207.645 86.36)
		)
		(stroke
			(width 0)
			(type default)
		)
	)
	(wire
		(pts
			(xy 189.23 169.545) (xy 196.85 169.545)
		)
		(stroke
			(width 0)
			(type default)
		)
	)
	(wire
		(pts
			(xy 234.315 86.36) (xy 234.315 88.265)
		)
		(stroke
			(width 0)
			(type default)
		)
	)
	(wire
		(pts
			(xy 250.825 125.73) (xy 266.7 125.73)
		)
		(stroke
			(width 0)
			(type default)
		)
	)
	(wire
		(pts
			(xy 232.41 187.325) (xy 232.41 187.96)
		)
		(stroke
			(width 0)
			(type default)
		)
	)
	(wire
		(pts
			(xy 196.85 169.545) (xy 240.665 169.545)
		)
		(stroke
			(width 0)
			(type default)
		)
	)
	(wire
		(pts
			(xy 190.5 94.615) (xy 190.5 93.345)
		)
		(stroke
			(width 0)
			(type default)
		)
	)
	(wire
		(pts
			(xy 196.85 169.545) (xy 196.85 173.355)
		)
		(stroke
			(width 0)
			(type default)
		)
	)
	(wire
		(pts
			(xy 227.33 91.44) (xy 227.33 92.71)
		)
		(stroke
			(width 0)
			(type default)
		)
	)
	(wire
		(pts
			(xy 226.06 91.44) (xy 227.33 91.44)
		)
		(stroke
			(width 0)
			(type default)
		)
	)
	(wire
		(pts
			(xy 182.88 86.36) (xy 182.88 74.93)
		)
		(stroke
			(width 0)
			(type default)
		)
	)
	(wire
		(pts
			(xy 182.245 130.81) (xy 210.82 130.81)
		)
		(stroke
			(width 0)
			(type default)
		)
	)
	(wire
		(pts
			(xy 240.665 182.245) (xy 240.665 181.61)
		)
		(stroke
			(width 0)
			(type default)
		)
	)
	(wire
		(pts
			(xy 232.41 135.89) (xy 241.3 135.89)
		)
		(stroke
			(width 0)
			(type default)
		)
	)
	(wire
		(pts
			(xy 182.245 181.61) (xy 189.23 181.61)
		)
		(stroke
			(width 0)
			(type default)
		)
	)
	(wire
		(pts
			(xy 259.08 128.27) (xy 259.08 134.62)
		)
		(stroke
			(width 0)
			(type default)
		)
	)
	(wire
		(pts
			(xy 182.245 128.27) (xy 210.82 128.27)
		)
		(stroke
			(width 0)
			(type default)
		)
	)
	(wire
		(pts
			(xy 234.315 74.93) (xy 235.585 74.93)
		)
		(stroke
			(width 0)
			(type default)
		)
	)
	(wire
		(pts
			(xy 220.98 74.93) (xy 229.235 74.93)
		)
		(stroke
			(width 0)
			(type default)
		)
	)
	(wire
		(pts
			(xy 226.06 184.15) (xy 226.695 184.15)
		)
		(stroke
			(width 0)
			(type default)
		)
	)
	(wire
		(pts
			(xy 232.41 128.27) (xy 245.745 128.27)
		)
		(stroke
			(width 0)
			(type default)
		)
	)
	(wire
		(pts
			(xy 229.235 74.295) (xy 229.235 74.93)
		)
		(stroke
			(width 0)
			(type default)
		)
	)
	(wire
		(pts
			(xy 274.32 142.24) (xy 274.32 153.67)
		)
		(stroke
			(width 0)
			(type default)
		)
	)
	(wire
		(pts
			(xy 250.825 123.19) (xy 274.32 123.19)
		)
		(stroke
			(width 0)
			(type default)
		)
	)
	(wire
		(pts
			(xy 182.245 184.15) (xy 196.85 184.15)
		)
		(stroke
			(width 0)
			(type default)
		)
	)
	(wire
		(pts
			(xy 232.41 120.65) (xy 245.745 120.65)
		)
		(stroke
			(width 0)
			(type default)
		)
	)
	(wire
		(pts
			(xy 189.23 178.435) (xy 189.23 181.61)
		)
		(stroke
			(width 0)
			(type default)
		)
	)
	(wire
		(pts
			(xy 196.85 178.435) (xy 196.85 184.15)
		)
		(stroke
			(width 0)
			(type default)
		)
	)
	(wire
		(pts
			(xy 190.5 86.36) (xy 197.485 86.36)
		)
		(stroke
			(width 0)
			(type default)
		)
	)
	(wire
		(pts
			(xy 226.06 181.61) (xy 232.41 181.61)
		)
		(stroke
			(width 0)
			(type default)
		)
	)
	(wire
		(pts
			(xy 240.665 169.545) (xy 248.92 169.545)
		)
		(stroke
			(width 0)
			(type default)
		)
	)
	(wire
		(pts
			(xy 232.41 133.35) (xy 241.3 133.35)
		)
		(stroke
			(width 0)
			(type default)
		)
	)
	(wire
		(pts
			(xy 250.825 120.65) (xy 281.94 120.65)
		)
		(stroke
			(width 0)
			(type default)
		)
	)
	(wire
		(pts
			(xy 190.5 86.36) (xy 190.5 88.265)
		)
		(stroke
			(width 0)
			(type default)
		)
	)
	(wire
		(pts
			(xy 182.88 74.93) (xy 181.61 74.93)
		)
		(stroke
			(width 0)
			(type default)
		)
	)
	(wire
		(pts
			(xy 182.88 120.65) (xy 210.82 120.65)
		)
		(stroke
			(width 0)
			(type default)
		)
	)
	(wire
		(pts
			(xy 274.32 123.19) (xy 274.32 134.62)
		)
		(stroke
			(width 0)
			(type default)
		)
	)
	(wire
		(pts
			(xy 196.85 186.69) (xy 196.85 187.96)
		)
		(stroke
			(width 0)
			(type default)
		)
	)
	(wire
		(pts
			(xy 281.94 142.24) (xy 281.94 153.67)
		)
		(stroke
			(width 0)
			(type default)
		)
	)
	(wire
		(pts
			(xy 240.665 169.545) (xy 240.665 181.61)
		)
		(stroke
			(width 0)
			(type default)
		)
	)
	(wire
		(pts
			(xy 234.315 93.345) (xy 234.315 94.615)
		)
		(stroke
			(width 0)
			(type default)
		)
	)
	(wire
		(pts
			(xy 199.39 140.97) (xy 210.82 140.97)
		)
		(stroke
			(width 0)
			(type default)
		)
	)
	(wire
		(pts
			(xy 226.695 184.15) (xy 226.695 187.96)
		)
		(stroke
			(width 0)
			(type default)
		)
	)
	(wire
		(pts
			(xy 281.94 120.65) (xy 281.94 134.62)
		)
		(stroke
			(width 0)
			(type default)
		)
	)
	(wire
		(pts
			(xy 240.665 187.325) (xy 240.665 187.96)
		)
		(stroke
			(width 0)
			(type default)
		)
	)
	(wire
		(pts
			(xy 232.41 125.73) (xy 245.745 125.73)
		)
		(stroke
			(width 0)
			(type default)
		)
	)
	(wire
		(pts
			(xy 199.39 146.05) (xy 210.82 146.05)
		)
		(stroke
			(width 0)
			(type default)
		)
	)
	(wire
		(pts
			(xy 266.7 125.73) (xy 266.7 134.62)
		)
		(stroke
			(width 0)
			(type default)
		)
	)
	(wire
		(pts
			(xy 199.39 138.43) (xy 199.39 123.19)
		)
		(stroke
			(width 0)
			(type default)
		)
	)
	(wire
		(pts
			(xy 199.39 138.43) (xy 210.82 138.43)
		)
		(stroke
			(width 0)
			(type default)
		)
	)
	(wire
		(pts
			(xy 189.23 169.545) (xy 189.23 173.355)
		)
		(stroke
			(width 0)
			(type default)
		)
	)
	(wire
		(pts
			(xy 232.41 123.19) (xy 245.745 123.19)
		)
		(stroke
			(width 0)
			(type default)
		)
	)
	(wire
		(pts
			(xy 250.825 128.27) (xy 259.08 128.27)
		)
		(stroke
			(width 0)
			(type default)
		)
	)
	(wire
		(pts
			(xy 199.39 140.97) (xy 199.39 138.43)
		)
		(stroke
			(width 0)
			(type default)
		)
	)
	(wire
		(pts
			(xy 215.9 74.93) (xy 182.88 74.93)
		)
		(stroke
			(width 0)
			(type default)
		)
	)
	(wire
		(pts
			(xy 234.315 86.36) (xy 234.315 74.93)
		)
		(stroke
			(width 0)
			(type default)
		)
	)
	(wire
		(pts
			(xy 202.565 86.36) (xy 207.645 86.36)
		)
		(stroke
			(width 0)
			(type default)
		)
	)
	(wire
		(pts
			(xy 226.06 86.36) (xy 234.315 86.36)
		)
		(stroke
			(width 0)
			(type default)
		)
	)
	(wire
		(pts
			(xy 196.85 186.69) (xy 205.74 186.69)
		)
		(stroke
			(width 0)
			(type default)
		)
	)
	(wire
		(pts
			(xy 196.85 184.15) (xy 205.74 184.15)
		)
		(stroke
			(width 0)
			(type default)
		)
	)
	(wire
		(pts
			(xy 189.23 181.61) (xy 205.74 181.61)
		)
		(stroke
			(width 0)
			(type default)
		)
	)
	(wire
		(pts
			(xy 232.41 182.245) (xy 232.41 181.61)
		)
		(stroke
			(width 0)
			(type default)
		)
	)
	(wire
		(pts
			(xy 199.39 149.86) (xy 199.39 146.05)
		)
		(stroke
			(width 0)
			(type default)
		)
	)
	(wire
		(pts
			(xy 182.88 86.36) (xy 190.5 86.36)
		)
		(stroke
			(width 0)
			(type default)
		)
	)
	(wire
		(pts
			(xy 199.39 123.19) (xy 210.82 123.19)
		)
		(stroke
			(width 0)
			(type default)
		)
	)
	(wire
		(pts
			(xy 266.7 142.24) (xy 266.7 153.67)
		)
		(stroke
			(width 0)
			(type default)
		)
	)
	(wire
		(pts
			(xy 207.645 86.36) (xy 210.82 86.36)
		)
		(stroke
			(width 0)
			(type default)
		)
	)
	(wire
		(pts
			(xy 232.41 181.61) (xy 240.665 181.61)
		)
		(stroke
			(width 0)
			(type default)
		)
	)
	(global_label "SCL"
		(shape input)
		(at 182.245 130.81 180)
		(fields_autoplaced yes)
		(effects
			(font
				(size 1.27 1.27)
			)
			(justify right)
		)
		(property "Intersheetrefs" "${INTERSHEET_REFS}"
			(at 127 36.83 0)
			(effects
				(font
					(size 1.27 1.27)
				)
				(hide yes)
			)
		)
	)
	(global_label "VDDLED"
		(shape input)
		(at 182.88 120.65 180)
		(fields_autoplaced yes)
		(effects
			(font
				(size 1.27 1.27)
			)
			(justify right)
		)
		(property "Intersheetrefs" "${INTERSHEET_REFS}"
			(at 105.41 184.15 0)
			(effects
				(font
					(size 1.27 1.27)
				)
				(hide yes)
			)
		)
	)
	(global_label "VDDLED"
		(shape output)
		(at 235.585 74.93 0)
		(fields_autoplaced yes)
		(effects
			(font
				(size 1.27 1.27)
			)
			(justify left)
		)
		(property "Intersheetrefs" "${INTERSHEET_REFS}"
			(at 244.9849 74.8506 0)
			(effects
				(font
					(size 1.27 1.27)
				)
				(justify left)
				(hide yes)
			)
		)
	)
	(global_label "VDD1"
		(shape input)
		(at 182.88 123.19 180)
		(fields_autoplaced yes)
		(effects
			(font
				(size 1.27 1.27)
			)
			(justify right)
		)
		(property "Intersheetrefs" "${INTERSHEET_REFS}"
			(at 105.41 181.61 0)
			(effects
				(font
					(size 1.27 1.27)
				)
				(hide yes)
			)
		)
	)
	(global_label "VDD1"
		(shape input)
		(at 248.92 169.545 0)
		(fields_autoplaced yes)
		(effects
			(font
				(size 1.27 1.27)
			)
			(justify left)
		)
		(property "Intersheetrefs" "${INTERSHEET_REFS}"
			(at 381 64.135 0)
			(effects
				(font
					(size 1.27 1.27)
				)
				(hide yes)
			)
		)
	)
	(global_label "VDD1"
		(shape input)
		(at 181.61 74.93 180)
		(fields_autoplaced yes)
		(effects
			(font
				(size 1.27 1.27)
			)
			(justify right)
		)
		(property "Intersheetrefs" "${INTERSHEET_REFS}"
			(at 143.51 130.81 0)
			(effects
				(font
					(size 1.27 1.27)
				)
				(hide yes)
			)
		)
	)
	(global_label "SDA"
		(shape input)
		(at 182.245 128.27 180)
		(fields_autoplaced yes)
		(effects
			(font
				(size 1.27 1.27)
			)
			(justify right)
		)
		(property "Intersheetrefs" "${INTERSHEET_REFS}"
			(at 127 36.83 0)
			(effects
				(font
					(size 1.27 1.27)
				)
				(hide yes)
			)
		)
	)
	(global_label "SDA"
		(shape input)
		(at 182.245 181.61 180)
		(fields_autoplaced yes)
		(effects
			(font
				(size 1.27 1.27)
			)
			(justify right)
		)
		(property "Intersheetrefs" "${INTERSHEET_REFS}"
			(at 127 36.83 0)
			(effects
				(font
					(size 1.27 1.27)
				)
				(hide yes)
			)
		)
	)
	(global_label "SCL"
		(shape input)
		(at 182.245 184.15 180)
		(fields_autoplaced yes)
		(effects
			(font
				(size 1.27 1.27)
			)
			(justify right)
		)
		(property "Intersheetrefs" "${INTERSHEET_REFS}"
			(at 127 36.83 0)
			(effects
				(font
					(size 1.27 1.27)
				)
				(hide yes)
			)
		)
	)
	(symbol
		(lib_id "antmicroCapacitors0402:C_4u7_0402")
		(at 190.5 93.345 90)
		(unit 1)
		(exclude_from_sim no)
		(in_bom yes)
		(on_board yes)
		(dnp no)
		(property "Reference" "C34"
			(at 191.135 90.17 90)
			(effects
				(font
					(size 1.27 1.27)
					(thickness 0.15)
				)
				(justify right top)
			)
		)
		(property "Value" "C_4u7_0402"
			(at 194.31 93.345 0)
			(effects
				(font
					(size 1.27 1.27)
					(thickness 0.15)
				)
				(justify left bottom)
				(hide yes)
			)
		)
		(property "Footprint" "antmicro-footprints:C_0402_1005Metric"
			(at 185.42 88.265 0)
			(effects
				(font
					(size 1.27 1.27)
					(thickness 0.15)
				)
				(justify left bottom)
				(hide yes)
			)
		)
		(property "Datasheet" " "
			(at 190.5 93.345 0)
			(effects
				(font
					(size 1.27 1.27)
					(thickness 0.15)
				)
				(justify left bottom)
				(hide yes)
			)
		)
		(property "Description" ""
			(at 190.5 93.345 0)
			(effects
				(font
					(size 1.27 1.27)
				)
			)
		)
		(property "Manufacturer" "Murata"
			(at 180.34 88.265 0)
			(effects
				(font
					(size 1.27 1.27)
					(thickness 0.15)
				)
				(justify left bottom)
				(hide yes)
			)
		)
		(property "MPN" "GRM155R61A475MEAAD"
			(at 182.88 88.265 0)
			(effects
				(font
					(size 1.27 1.27)
					(thickness 0.15)
				)
				(justify left bottom)
				(hide yes)
			)
		)
		(property "Val" "4u7"
			(at 191.135 93.98 90)
			(effects
				(font
					(size 1.27 1.27)
					(thickness 0.15)
				)
				(justify right top)
			)
		)
		(property "License" "Apache-2.0"
			(at 213.36 73.025 0)
			(effects
				(font
					(size 1.27 1.27)
					(thickness 0.15)
				)
				(justify left bottom)
				(hide yes)
			)
		)
		(property "Author" "Antmicro"
			(at 215.9 73.025 0)
			(effects
				(font
					(size 1.27 1.27)
					(thickness 0.15)
				)
				(justify left bottom)
				(hide yes)
			)
		)
		(property "Voltage" ""
			(at 218.44 73.025 0)
			(effects
				(font
					(size 1.27 1.27)
				)
				(justify left bottom)
				(hide yes)
			)
		)
		(property "Dielectric" ""
			(at 220.98 73.025 0)
			(effects
				(font
					(size 1.27 1.27)
				)
				(justify left bottom)
				(hide yes)
			)
		)
		(pin "1"
		)
		(pin "2"
		)
		(instances
			(project "lpddr4-testbed"
				(path ""
					(reference "C34")
					(unit 1)
				)
			)
		)
	)
	(symbol
		(lib_id "antmicroCapacitors0402:C_4u7_0402")
		(at 234.315 93.345 90)
		(unit 1)
		(exclude_from_sim no)
		(in_bom yes)
		(on_board yes)
		(dnp no)
		(property "Reference" "C37"
			(at 234.95 88.9 90)
			(effects
				(font
					(size 1.27 1.27)
					(thickness 0.15)
				)
				(justify right)
			)
		)
		(property "Value" "C_4u7_0402"
			(at 238.125 93.345 0)
			(effects
				(font
					(size 1.27 1.27)
					(thickness 0.15)
				)
				(justify left bottom)
				(hide yes)
			)
		)
		(property "Footprint" "antmicro-footprints:C_0402_1005Metric"
			(at 229.235 88.265 0)
			(effects
				(font
					(size 1.27 1.27)
					(thickness 0.15)
				)
				(justify left bottom)
				(hide yes)
			)
		)
		(property "Datasheet" " "
			(at 234.315 93.345 0)
			(effects
				(font
					(size 1.27 1.27)
					(thickness 0.15)
				)
				(justify left bottom)
				(hide yes)
			)
		)
		(property "Description" ""
			(at 234.315 93.345 0)
			(effects
				(font
					(size 1.27 1.27)
				)
			)
		)
		(property "Manufacturer" "Murata"
			(at 224.155 88.265 0)
			(effects
				(font
					(size 1.27 1.27)
					(thickness 0.15)
				)
				(justify left bottom)
				(hide yes)
			)
		)
		(property "MPN" "GRM155R61A475MEAAD"
			(at 226.695 88.265 0)
			(effects
				(font
					(size 1.27 1.27)
					(thickness 0.15)
				)
				(justify left bottom)
				(hide yes)
			)
		)
		(property "Val" "4u7"
			(at 234.95 92.71 90)
			(effects
				(font
					(size 1.27 1.27)
					(thickness 0.15)
				)
				(justify right)
			)
		)
		(property "License" "Apache-2.0"
			(at 257.175 73.025 0)
			(effects
				(font
					(size 1.27 1.27)
					(thickness 0.15)
				)
				(justify left bottom)
				(hide yes)
			)
		)
		(property "Author" "Antmicro"
			(at 259.715 73.025 0)
			(effects
				(font
					(size 1.27 1.27)
					(thickness 0.15)
				)
				(justify left bottom)
				(hide yes)
			)
		)
		(pin "1"
		)
		(pin "2"
		)
		(instances
			(project "lpddr4-testbed"
				(path ""
					(reference "C37")
					(unit 1)
				)
			)
		)
	)
	(symbol
		(lib_id "antmicroResistors0402:R_0R_0402")
		(at 215.9 74.93 0)
		(unit 1)
		(exclude_from_sim no)
		(in_bom no)
		(on_board yes)
		(dnp yes)
		(property "Reference" "R8"
			(at 220.98 74.93 0)
			(effects
				(font
					(size 1.27 1.27)
					(thickness 0.15)
				)
				(justify left bottom)
			)
		)
		(property "Value" "R_0R_0402"
			(at 215.9 78.74 0)
			(effects
				(font
					(size 1.27 1.27)
					(thickness 0.15)
				)
				(justify left bottom)
				(hide yes)
			)
		)
		(property "Footprint" "antmicro-footprints:R_0402_1005Metric"
			(at 220.98 69.85 0)
			(effects
				(font
					(size 1.27 1.27)
					(thickness 0.15)
				)
				(justify left bottom)
				(hide yes)
			)
		)
		(property "Datasheet" "https://industrial.panasonic.com/cdbs/www-data/pdf/RDA0000/AOA0000C301.pdf"
			(at 215.9 74.93 0)
			(effects
				(font
					(size 1.27 1.27)
					(thickness 0.15)
				)
				(justify left bottom)
				(hide yes)
			)
		)
		(property "Description" ""
			(at 215.9 74.93 0)
			(effects
				(font
					(size 1.27 1.27)
				)
			)
		)
		(property "Manufacturer" "Panasonic"
			(at 220.98 64.77 0)
			(effects
				(font
					(size 1.27 1.27)
					(thickness 0.15)
				)
				(justify left bottom)
				(hide yes)
			)
		)
		(property "MPN" "ERJ2GE0R00X"
			(at 220.98 67.31 0)
			(effects
				(font
					(size 1.27 1.27)
					(thickness 0.15)
				)
				(justify left bottom)
				(hide yes)
			)
		)
		(property "Val" "0R"
			(at 213.36 74.93 0)
			(effects
				(font
					(size 1.27 1.27)
					(thickness 0.15)
				)
				(justify left bottom)
			)
		)
		(property "License" "Apache-2.0"
			(at 236.22 100.33 0)
			(effects
				(font
					(size 1.27 1.27)
					(thickness 0.15)
				)
				(justify left bottom)
				(hide yes)
			)
		)
		(property "Author" "Antmicro"
			(at 236.22 102.87 0)
			(effects
				(font
					(size 1.27 1.27)
					(thickness 0.15)
				)
				(justify left bottom)
				(hide yes)
			)
		)
		(property "Tolerance" "~"
			(at 236.22 85.09 0)
			(effects
				(font
					(size 1.27 1.27)
				)
				(justify left bottom)
				(hide yes)
			)
		)
		(property "Current" "1A"
			(at 236.22 105.41 0)
			(effects
				(font
					(size 1.27 1.27)
					(thickness 0.15)
				)
				(justify left bottom)
				(hide yes)
			)
		)
		(pin "1"
		)
		(pin "2"
		)
		(instances
			(project "lpddr4-testbed"
				(path ""
					(reference "R8")
					(unit 1)
				)
			)
		)
	)
	(symbol
		(lib_id "antmicropower:GND")
		(at 190.5 94.615 0)
		(unit 1)
		(exclude_from_sim no)
		(in_bom yes)
		(on_board yes)
		(dnp no)
		(property "Reference" "#PWR0106"
			(at 190.5 100.965 0)
			(effects
				(font
					(size 1.27 1.27)
				)
				(hide yes)
			)
		)
		(property "Value" "GND"
			(at 190.5 98.425 0)
			(effects
				(font
					(size 1.27 1.27)
				)
			)
		)
		(property "Footprint" ""
			(at 190.5 94.615 0)
			(effects
				(font
					(size 1.27 1.27)
				)
				(hide yes)
			)
		)
		(property "Datasheet" ""
			(at 190.5 94.615 0)
			(effects
				(font
					(size 1.27 1.27)
				)
				(hide yes)
			)
		)
		(property "Description" ""
			(at 190.5 94.615 0)
			(effects
				(font
					(size 1.27 1.27)
				)
			)
		)
		(pin "1"
		)
		(instances
			(project "lpddr4-testbed"
				(path ""
					(reference "#PWR0106")
					(unit 1)
				)
			)
		)
	)
	(symbol
		(lib_id "antmicropower:GND")
		(at 234.315 94.615 0)
		(unit 1)
		(exclude_from_sim no)
		(in_bom yes)
		(on_board yes)
		(dnp no)
		(property "Reference" "#PWR0107"
			(at 234.315 100.965 0)
			(effects
				(font
					(size 1.27 1.27)
				)
				(hide yes)
			)
		)
		(property "Value" "GND"
			(at 234.315 98.425 0)
			(effects
				(font
					(size 1.27 1.27)
				)
			)
		)
		(property "Footprint" ""
			(at 234.315 94.615 0)
			(effects
				(font
					(size 1.27 1.27)
				)
				(hide yes)
			)
		)
		(property "Datasheet" ""
			(at 234.315 94.615 0)
			(effects
				(font
					(size 1.27 1.27)
				)
				(hide yes)
			)
		)
		(property "Description" ""
			(at 234.315 94.615 0)
			(effects
				(font
					(size 1.27 1.27)
				)
			)
		)
		(pin "1"
		)
		(instances
			(project "lpddr4-testbed"
				(path ""
					(reference "#PWR0107")
					(unit 1)
				)
			)
		)
	)
	(symbol
		(lib_id "antmicropower:GND")
		(at 227.33 92.71 0)
		(unit 1)
		(exclude_from_sim no)
		(in_bom yes)
		(on_board yes)
		(dnp no)
		(property "Reference" "#PWR0108"
			(at 227.33 99.06 0)
			(effects
				(font
					(size 1.27 1.27)
				)
				(hide yes)
			)
		)
		(property "Value" "GND"
			(at 227.33 96.52 0)
			(effects
				(font
					(size 1.27 1.27)
				)
			)
		)
		(property "Footprint" ""
			(at 227.33 92.71 0)
			(effects
				(font
					(size 1.27 1.27)
				)
				(hide yes)
			)
		)
		(property "Datasheet" ""
			(at 227.33 92.71 0)
			(effects
				(font
					(size 1.27 1.27)
				)
				(hide yes)
			)
		)
		(property "Description" ""
			(at 227.33 92.71 0)
			(effects
				(font
					(size 1.27 1.27)
				)
			)
		)
		(pin "1"
		)
		(instances
			(project "lpddr4-testbed"
				(path ""
					(reference "#PWR0108")
					(unit 1)
				)
			)
		)
	)
	(symbol
		(lib_id "antmicroResistors0402:R_10k_0402")
		(at 189.23 173.355 270)
		(unit 1)
		(exclude_from_sim no)
		(in_bom yes)
		(on_board yes)
		(dnp no)
		(property "Reference" "R13"
			(at 190.5 174.625 90)
			(effects
				(font
					(size 1.27 1.27)
					(thickness 0.15)
				)
				(justify left)
			)
		)
		(property "Value" "R_10k_0402"
			(at 185.42 173.355 0)
			(effects
				(font
					(size 1.27 1.27)
					(thickness 0.15)
				)
				(justify left bottom)
				(hide yes)
			)
		)
		(property "Footprint" "antmicro-footprints:R_0402_1005Metric"
			(at 194.31 178.435 0)
			(effects
				(font
					(size 1.27 1.27)
					(thickness 0.15)
				)
				(justify left bottom)
				(hide yes)
			)
		)
		(property "Datasheet" ""
			(at 189.23 173.355 0)
			(effects
				(font
					(size 1.27 1.27)
					(thickness 0.15)
				)
				(justify left bottom)
				(hide yes)
			)
		)
		(property "Description" ""
			(at 189.23 173.355 0)
			(effects
				(font
					(size 1.27 1.27)
				)
			)
		)
		(property "Manufacturer" "VISHAY"
			(at 199.39 178.435 0)
			(effects
				(font
					(size 1.27 1.27)
					(thickness 0.15)
				)
				(justify left bottom)
				(hide yes)
			)
		)
		(property "MPN" "CRCW040210K0FKEDHP"
			(at 196.85 178.435 0)
			(effects
				(font
					(size 1.27 1.27)
					(thickness 0.15)
				)
				(justify left bottom)
				(hide yes)
			)
		)
		(property "Val" "10k"
			(at 190.5 177.165 90)
			(effects
				(font
					(size 1.27 1.27)
					(thickness 0.15)
				)
				(justify left)
			)
		)
		(property "License" "Apache-2.0"
			(at 163.83 193.675 0)
			(effects
				(font
					(size 1.27 1.27)
					(thickness 0.15)
				)
				(justify left bottom)
				(hide yes)
			)
		)
		(property "Author" "Antmicro"
			(at 161.29 193.675 0)
			(effects
				(font
					(size 1.27 1.27)
					(thickness 0.15)
				)
				(justify left bottom)
				(hide yes)
			)
		)
		(property "Tolerance" "1%"
			(at 179.07 193.675 0)
			(effects
				(font
					(size 1.27 1.27)
				)
				(justify left bottom)
				(hide yes)
			)
		)
		(pin "1"
		)
		(pin "2"
		)
		(instances
			(project "lpddr4-testbed"
				(path ""
					(reference "R13")
					(unit 1)
				)
			)
		)
	)
	(symbol
		(lib_id "antmicroResistors0402:R_220R_0402")
		(at 245.745 120.65 0)
		(unit 1)
		(exclude_from_sim no)
		(in_bom yes)
		(on_board yes)
		(dnp no)
		(property "Reference" "R9"
			(at 250.825 120.65 0)
			(effects
				(font
					(size 1.27 1.27)
					(thickness 0.15)
				)
				(justify left bottom)
			)
		)
		(property "Value" "R_220R_0402"
			(at 245.745 124.46 0)
			(effects
				(font
					(size 1.27 1.27)
					(thickness 0.15)
				)
				(justify left bottom)
				(hide yes)
			)
		)
		(property "Footprint" "antmicro-footprints:R_0402_1005Metric"
			(at 250.825 115.57 0)
			(effects
				(font
					(size 1.27 1.27)
					(thickness 0.15)
				)
				(justify left bottom)
				(hide yes)
			)
		)
		(property "Datasheet" ""
			(at 245.745 120.65 0)
			(effects
				(font
					(size 1.27 1.27)
					(thickness 0.15)
				)
				(justify left bottom)
				(hide yes)
			)
		)
		(property "Description" ""
			(at 245.745 120.65 0)
			(effects
				(font
					(size 1.27 1.27)
				)
			)
		)
		(property "Manufacturer" "Panasonic"
			(at 250.825 110.49 0)
			(effects
				(font
					(size 1.27 1.27)
					(thickness 0.15)
				)
				(justify left bottom)
				(hide yes)
			)
		)
		(property "MPN" "ERJ2GEJ221X"
			(at 250.825 113.03 0)
			(effects
				(font
					(size 1.27 1.27)
					(thickness 0.15)
				)
				(justify left bottom)
				(hide yes)
			)
		)
		(property "Val" "220R"
			(at 240.665 120.65 0)
			(effects
				(font
					(size 1.27 1.27)
					(thickness 0.15)
				)
				(justify left bottom)
			)
		)
		(property "License" "Apache-2.0"
			(at 266.065 146.05 0)
			(effects
				(font
					(size 1.27 1.27)
					(thickness 0.15)
				)
				(justify left bottom)
				(hide yes)
			)
		)
		(property "Author" "Antmicro"
			(at 266.065 148.59 0)
			(effects
				(font
					(size 1.27 1.27)
					(thickness 0.15)
				)
				(justify left bottom)
				(hide yes)
			)
		)
		(property "Tolerance" "1%"
			(at 266.065 130.81 0)
			(effects
				(font
					(size 1.27 1.27)
				)
				(justify left bottom)
				(hide yes)
			)
		)
		(pin "1"
		)
		(pin "2"
		)
		(instances
			(project "lpddr4-testbed"
				(path ""
					(reference "R9")
					(unit 1)
				)
			)
		)
	)
	(symbol
		(lib_id "antmicroResistors0402:R_220R_0402")
		(at 245.745 123.19 0)
		(unit 1)
		(exclude_from_sim no)
		(in_bom yes)
		(on_board yes)
		(dnp no)
		(property "Reference" "R10"
			(at 250.825 123.19 0)
			(effects
				(font
					(size 1.27 1.27)
					(thickness 0.15)
				)
				(justify left bottom)
			)
		)
		(property "Value" "R_220R_0402"
			(at 245.745 127 0)
			(effects
				(font
					(size 1.27 1.27)
					(thickness 0.15)
				)
				(justify left bottom)
				(hide yes)
			)
		)
		(property "Footprint" "antmicro-footprints:R_0402_1005Metric"
			(at 250.825 118.11 0)
			(effects
				(font
					(size 1.27 1.27)
					(thickness 0.15)
				)
				(justify left bottom)
				(hide yes)
			)
		)
		(property "Datasheet" ""
			(at 245.745 123.19 0)
			(effects
				(font
					(size 1.27 1.27)
					(thickness 0.15)
				)
				(justify left bottom)
				(hide yes)
			)
		)
		(property "Description" ""
			(at 245.745 123.19 0)
			(effects
				(font
					(size 1.27 1.27)
				)
			)
		)
		(property "Manufacturer" "Panasonic"
			(at 250.825 113.03 0)
			(effects
				(font
					(size 1.27 1.27)
					(thickness 0.15)
				)
				(justify left bottom)
				(hide yes)
			)
		)
		(property "MPN" "ERJ2GEJ221X"
			(at 250.825 115.57 0)
			(effects
				(font
					(size 1.27 1.27)
					(thickness 0.15)
				)
				(justify left bottom)
				(hide yes)
			)
		)
		(property "Val" "220R"
			(at 240.665 123.19 0)
			(effects
				(font
					(size 1.27 1.27)
					(thickness 0.15)
				)
				(justify left bottom)
			)
		)
		(property "License" "Apache-2.0"
			(at 266.065 148.59 0)
			(effects
				(font
					(size 1.27 1.27)
					(thickness 0.15)
				)
				(justify left bottom)
				(hide yes)
			)
		)
		(property "Author" "Antmicro"
			(at 266.065 151.13 0)
			(effects
				(font
					(size 1.27 1.27)
					(thickness 0.15)
				)
				(justify left bottom)
				(hide yes)
			)
		)
		(property "Tolerance" "1%"
			(at 266.065 133.35 0)
			(effects
				(font
					(size 1.27 1.27)
				)
				(justify left bottom)
				(hide yes)
			)
		)
		(pin "1"
		)
		(pin "2"
		)
		(instances
			(project "lpddr4-testbed"
				(path ""
					(reference "R10")
					(unit 1)
				)
			)
		)
	)
	(symbol
		(lib_id "antmicroResistors0402:R_220R_0402")
		(at 245.745 125.73 0)
		(unit 1)
		(exclude_from_sim no)
		(in_bom yes)
		(on_board yes)
		(dnp no)
		(property "Reference" "R11"
			(at 250.825 125.73 0)
			(effects
				(font
					(size 1.27 1.27)
					(thickness 0.15)
				)
				(justify left bottom)
			)
		)
		(property "Value" "R_220R_0402"
			(at 245.745 129.54 0)
			(effects
				(font
					(size 1.27 1.27)
					(thickness 0.15)
				)
				(justify left bottom)
				(hide yes)
			)
		)
		(property "Footprint" "antmicro-footprints:R_0402_1005Metric"
			(at 250.825 120.65 0)
			(effects
				(font
					(size 1.27 1.27)
					(thickness 0.15)
				)
				(justify left bottom)
				(hide yes)
			)
		)
		(property "Datasheet" ""
			(at 245.745 125.73 0)
			(effects
				(font
					(size 1.27 1.27)
					(thickness 0.15)
				)
				(justify left bottom)
				(hide yes)
			)
		)
		(property "Description" ""
			(at 245.745 125.73 0)
			(effects
				(font
					(size 1.27 1.27)
				)
			)
		)
		(property "Manufacturer" "Panasonic"
			(at 250.825 115.57 0)
			(effects
				(font
					(size 1.27 1.27)
					(thickness 0.15)
				)
				(justify left bottom)
				(hide yes)
			)
		)
		(property "MPN" "ERJ2GEJ221X"
			(at 250.825 118.11 0)
			(effects
				(font
					(size 1.27 1.27)
					(thickness 0.15)
				)
				(justify left bottom)
				(hide yes)
			)
		)
		(property "Val" "220R"
			(at 240.665 125.73 0)
			(effects
				(font
					(size 1.27 1.27)
					(thickness 0.15)
				)
				(justify left bottom)
			)
		)
		(property "License" "Apache-2.0"
			(at 266.065 151.13 0)
			(effects
				(font
					(size 1.27 1.27)
					(thickness 0.15)
				)
				(justify left bottom)
				(hide yes)
			)
		)
		(property "Author" "Antmicro"
			(at 266.065 153.67 0)
			(effects
				(font
					(size 1.27 1.27)
					(thickness 0.15)
				)
				(justify left bottom)
				(hide yes)
			)
		)
		(property "Tolerance" "1%"
			(at 266.065 135.89 0)
			(effects
				(font
					(size 1.27 1.27)
				)
				(justify left bottom)
				(hide yes)
			)
		)
		(pin "1"
		)
		(pin "2"
		)
		(instances
			(project "lpddr4-testbed"
				(path ""
					(reference "R11")
					(unit 1)
				)
			)
		)
	)
	(symbol
		(lib_id "antmicroResistors0402:R_220R_0402")
		(at 245.745 128.27 0)
		(unit 1)
		(exclude_from_sim no)
		(in_bom yes)
		(on_board yes)
		(dnp no)
		(property "Reference" "R12"
			(at 250.825 128.27 0)
			(effects
				(font
					(size 1.27 1.27)
					(thickness 0.15)
				)
				(justify left bottom)
			)
		)
		(property "Value" "R_220R_0402"
			(at 245.745 132.08 0)
			(effects
				(font
					(size 1.27 1.27)
					(thickness 0.15)
				)
				(justify left bottom)
				(hide yes)
			)
		)
		(property "Footprint" "antmicro-footprints:R_0402_1005Metric"
			(at 250.825 123.19 0)
			(effects
				(font
					(size 1.27 1.27)
					(thickness 0.15)
				)
				(justify left bottom)
				(hide yes)
			)
		)
		(property "Datasheet" ""
			(at 245.745 128.27 0)
			(effects
				(font
					(size 1.27 1.27)
					(thickness 0.15)
				)
				(justify left bottom)
				(hide yes)
			)
		)
		(property "Description" ""
			(at 245.745 128.27 0)
			(effects
				(font
					(size 1.27 1.27)
				)
			)
		)
		(property "Manufacturer" "Panasonic"
			(at 250.825 118.11 0)
			(effects
				(font
					(size 1.27 1.27)
					(thickness 0.15)
				)
				(justify left bottom)
				(hide yes)
			)
		)
		(property "MPN" "ERJ2GEJ221X"
			(at 250.825 120.65 0)
			(effects
				(font
					(size 1.27 1.27)
					(thickness 0.15)
				)
				(justify left bottom)
				(hide yes)
			)
		)
		(property "Val" "220R"
			(at 240.665 128.27 0)
			(effects
				(font
					(size 1.27 1.27)
					(thickness 0.15)
				)
				(justify left bottom)
			)
		)
		(property "License" "Apache-2.0"
			(at 266.065 153.67 0)
			(effects
				(font
					(size 1.27 1.27)
					(thickness 0.15)
				)
				(justify left bottom)
				(hide yes)
			)
		)
		(property "Author" "Antmicro"
			(at 266.065 156.21 0)
			(effects
				(font
					(size 1.27 1.27)
					(thickness 0.15)
				)
				(justify left bottom)
				(hide yes)
			)
		)
		(property "Tolerance" "1%"
			(at 266.065 138.43 0)
			(effects
				(font
					(size 1.27 1.27)
				)
				(justify left bottom)
				(hide yes)
			)
		)
		(pin "1"
		)
		(pin "2"
		)
		(instances
			(project "lpddr4-testbed"
				(path ""
					(reference "R12")
					(unit 1)
				)
			)
		)
	)
	(symbol
		(lib_id "antmicroCapacitors0402:C_100n_0402")
		(at 232.41 187.325 90)
		(unit 1)
		(exclude_from_sim no)
		(in_bom yes)
		(on_board yes)
		(dnp no)
		(property "Reference" "C38"
			(at 233.045 182.88 90)
			(effects
				(font
					(size 1.27 1.27)
					(thickness 0.15)
				)
				(justify right)
			)
		)
		(property "Value" "C_100n_0402"
			(at 236.22 187.325 0)
			(effects
				(font
					(size 1.27 1.27)
					(thickness 0.15)
				)
				(justify left bottom)
				(hide yes)
			)
		)
		(property "Footprint" "antmicro-footprints:C_0402_1005Metric"
			(at 227.33 182.245 0)
			(effects
				(font
					(size 1.27 1.27)
					(thickness 0.15)
				)
				(justify left bottom)
				(hide yes)
			)
		)
		(property "Datasheet" ""
			(at 232.41 187.325 0)
			(effects
				(font
					(size 1.27 1.27)
					(thickness 0.15)
				)
				(justify left bottom)
				(hide yes)
			)
		)
		(property "Description" ""
			(at 232.41 187.325 0)
			(effects
				(font
					(size 1.27 1.27)
				)
			)
		)
		(property "Manufacturer" "Walsin"
			(at 222.25 182.245 0)
			(effects
				(font
					(size 1.27 1.27)
					(thickness 0.15)
				)
				(justify left bottom)
				(hide yes)
			)
		)
		(property "MPN" "0402X104K6R3CT"
			(at 224.79 182.245 0)
			(effects
				(font
					(size 1.27 1.27)
					(thickness 0.15)
				)
				(justify left bottom)
				(hide yes)
			)
		)
		(property "Val" "100n"
			(at 233.045 186.69 90)
			(effects
				(font
					(size 1.27 1.27)
					(thickness 0.15)
				)
				(justify right)
			)
		)
		(property "License" "Apache-2.0"
			(at 255.27 167.005 0)
			(effects
				(font
					(size 1.27 1.27)
					(thickness 0.15)
				)
				(justify left bottom)
				(hide yes)
			)
		)
		(property "Author" "Antmicro"
			(at 257.81 167.005 0)
			(effects
				(font
					(size 1.27 1.27)
					(thickness 0.15)
				)
				(justify left bottom)
				(hide yes)
			)
		)
		(property "Voltage" "50V"
			(at 260.35 167.005 0)
			(effects
				(font
					(size 1.27 1.27)
				)
				(justify left bottom)
				(hide yes)
			)
		)
		(property "Dielectric" "X5R"
			(at 262.89 167.005 0)
			(effects
				(font
					(size 1.27 1.27)
				)
				(justify left bottom)
				(hide yes)
			)
		)
		(pin "1"
		)
		(pin "2"
		)
		(instances
			(project "lpddr4-testbed"
				(path ""
					(reference "C38")
					(unit 1)
				)
			)
		)
	)
	(symbol
		(lib_id "antmicropower:GND")
		(at 259.08 153.67 0)
		(unit 1)
		(exclude_from_sim no)
		(in_bom yes)
		(on_board yes)
		(dnp no)
		(property "Reference" "#PWR0109"
			(at 259.08 160.02 0)
			(effects
				(font
					(size 1.27 1.27)
				)
				(hide yes)
			)
		)
		(property "Value" "GND"
			(at 259.207 158.0642 0)
			(effects
				(font
					(size 1.27 1.27)
				)
			)
		)
		(property "Footprint" ""
			(at 259.08 153.67 0)
			(effects
				(font
					(size 1.27 1.27)
				)
				(hide yes)
			)
		)
		(property "Datasheet" ""
			(at 259.08 153.67 0)
			(effects
				(font
					(size 1.27 1.27)
				)
				(hide yes)
			)
		)
		(property "Description" ""
			(at 259.08 153.67 0)
			(effects
				(font
					(size 1.27 1.27)
				)
			)
		)
		(pin "1"
		)
		(instances
			(project "lpddr4-testbed"
				(path ""
					(reference "#PWR0109")
					(unit 1)
				)
			)
		)
	)
	(symbol
		(lib_id "antmicropower:GND")
		(at 266.7 153.67 0)
		(unit 1)
		(exclude_from_sim no)
		(in_bom yes)
		(on_board yes)
		(dnp no)
		(property "Reference" "#PWR0110"
			(at 266.7 160.02 0)
			(effects
				(font
					(size 1.27 1.27)
				)
				(hide yes)
			)
		)
		(property "Value" "GND"
			(at 266.827 158.0642 0)
			(effects
				(font
					(size 1.27 1.27)
				)
			)
		)
		(property "Footprint" ""
			(at 266.7 153.67 0)
			(effects
				(font
					(size 1.27 1.27)
				)
				(hide yes)
			)
		)
		(property "Datasheet" ""
			(at 266.7 153.67 0)
			(effects
				(font
					(size 1.27 1.27)
				)
				(hide yes)
			)
		)
		(property "Description" ""
			(at 266.7 153.67 0)
			(effects
				(font
					(size 1.27 1.27)
				)
			)
		)
		(pin "1"
		)
		(instances
			(project "lpddr4-testbed"
				(path ""
					(reference "#PWR0110")
					(unit 1)
				)
			)
		)
	)
	(symbol
		(lib_id "antmicropower:GND")
		(at 274.32 153.67 0)
		(unit 1)
		(exclude_from_sim no)
		(in_bom yes)
		(on_board yes)
		(dnp no)
		(property "Reference" "#PWR0111"
			(at 274.32 160.02 0)
			(effects
				(font
					(size 1.27 1.27)
				)
				(hide yes)
			)
		)
		(property "Value" "GND"
			(at 274.447 158.0642 0)
			(effects
				(font
					(size 1.27 1.27)
				)
			)
		)
		(property "Footprint" ""
			(at 274.32 153.67 0)
			(effects
				(font
					(size 1.27 1.27)
				)
				(hide yes)
			)
		)
		(property "Datasheet" ""
			(at 274.32 153.67 0)
			(effects
				(font
					(size 1.27 1.27)
				)
				(hide yes)
			)
		)
		(property "Description" ""
			(at 274.32 153.67 0)
			(effects
				(font
					(size 1.27 1.27)
				)
			)
		)
		(pin "1"
		)
		(instances
			(project "lpddr4-testbed"
				(path ""
					(reference "#PWR0111")
					(unit 1)
				)
			)
		)
	)
	(symbol
		(lib_id "antmicropower:GND")
		(at 281.94 153.67 0)
		(unit 1)
		(exclude_from_sim no)
		(in_bom yes)
		(on_board yes)
		(dnp no)
		(property "Reference" "#PWR0112"
			(at 281.94 160.02 0)
			(effects
				(font
					(size 1.27 1.27)
				)
				(hide yes)
			)
		)
		(property "Value" "GND"
			(at 282.067 158.0642 0)
			(effects
				(font
					(size 1.27 1.27)
				)
			)
		)
		(property "Footprint" ""
			(at 281.94 153.67 0)
			(effects
				(font
					(size 1.27 1.27)
				)
				(hide yes)
			)
		)
		(property "Datasheet" ""
			(at 281.94 153.67 0)
			(effects
				(font
					(size 1.27 1.27)
				)
				(hide yes)
			)
		)
		(property "Description" ""
			(at 281.94 153.67 0)
			(effects
				(font
					(size 1.27 1.27)
				)
			)
		)
		(pin "1"
		)
		(instances
			(project "lpddr4-testbed"
				(path ""
					(reference "#PWR0112")
					(unit 1)
				)
			)
		)
	)
	(symbol
		(lib_id "antmicropower:GND")
		(at 199.39 149.86 0)
		(unit 1)
		(exclude_from_sim no)
		(in_bom yes)
		(on_board yes)
		(dnp no)
		(property "Reference" "#PWR0113"
			(at 199.39 156.21 0)
			(effects
				(font
					(size 1.27 1.27)
				)
				(hide yes)
			)
		)
		(property "Value" "GND"
			(at 199.517 154.2542 0)
			(effects
				(font
					(size 1.27 1.27)
				)
			)
		)
		(property "Footprint" ""
			(at 199.39 149.86 0)
			(effects
				(font
					(size 1.27 1.27)
				)
				(hide yes)
			)
		)
		(property "Datasheet" ""
			(at 199.39 149.86 0)
			(effects
				(font
					(size 1.27 1.27)
				)
				(hide yes)
			)
		)
		(property "Description" ""
			(at 199.39 149.86 0)
			(effects
				(font
					(size 1.27 1.27)
				)
			)
		)
		(pin "1"
		)
		(instances
			(project "lpddr4-testbed"
				(path ""
					(reference "#PWR0113")
					(unit 1)
				)
			)
		)
	)
	(symbol
		(lib_id "antmicroResistors0402:R_10k_0402")
		(at 196.85 173.355 270)
		(unit 1)
		(exclude_from_sim no)
		(in_bom yes)
		(on_board yes)
		(dnp no)
		(property "Reference" "R14"
			(at 198.12 174.625 90)
			(effects
				(font
					(size 1.27 1.27)
					(thickness 0.15)
				)
				(justify left)
			)
		)
		(property "Value" "R_10k_0402"
			(at 193.04 173.355 0)
			(effects
				(font
					(size 1.27 1.27)
					(thickness 0.15)
				)
				(justify left bottom)
				(hide yes)
			)
		)
		(property "Footprint" "antmicro-footprints:R_0402_1005Metric"
			(at 201.93 178.435 0)
			(effects
				(font
					(size 1.27 1.27)
					(thickness 0.15)
				)
				(justify left bottom)
				(hide yes)
			)
		)
		(property "Datasheet" ""
			(at 196.85 173.355 0)
			(effects
				(font
					(size 1.27 1.27)
					(thickness 0.15)
				)
				(justify left bottom)
				(hide yes)
			)
		)
		(property "Description" ""
			(at 196.85 173.355 0)
			(effects
				(font
					(size 1.27 1.27)
				)
			)
		)
		(property "Manufacturer" "VISHAY"
			(at 207.01 178.435 0)
			(effects
				(font
					(size 1.27 1.27)
					(thickness 0.15)
				)
				(justify left bottom)
				(hide yes)
			)
		)
		(property "MPN" "CRCW040210K0FKEDHP"
			(at 204.47 178.435 0)
			(effects
				(font
					(size 1.27 1.27)
					(thickness 0.15)
				)
				(justify left bottom)
				(hide yes)
			)
		)
		(property "Val" "10k"
			(at 198.12 177.165 90)
			(effects
				(font
					(size 1.27 1.27)
					(thickness 0.15)
				)
				(justify left)
			)
		)
		(property "License" "Apache-2.0"
			(at 171.45 193.675 0)
			(effects
				(font
					(size 1.27 1.27)
					(thickness 0.15)
				)
				(justify left bottom)
				(hide yes)
			)
		)
		(property "Author" "Antmicro"
			(at 168.91 193.675 0)
			(effects
				(font
					(size 1.27 1.27)
					(thickness 0.15)
				)
				(justify left bottom)
				(hide yes)
			)
		)
		(property "Tolerance" "1%"
			(at 186.69 193.675 0)
			(effects
				(font
					(size 1.27 1.27)
				)
				(justify left bottom)
				(hide yes)
			)
		)
		(pin "1"
		)
		(pin "2"
		)
		(instances
			(project "lpddr4-testbed"
				(path ""
					(reference "R14")
					(unit 1)
				)
			)
		)
	)
	(symbol
		(lib_id "antmicropower:GND")
		(at 196.85 187.96 0)
		(unit 1)
		(exclude_from_sim no)
		(in_bom yes)
		(on_board yes)
		(dnp no)
		(property "Reference" "#PWR0114"
			(at 196.85 194.31 0)
			(effects
				(font
					(size 1.27 1.27)
				)
				(hide yes)
			)
		)
		(property "Value" "GND"
			(at 196.977 192.3542 0)
			(effects
				(font
					(size 1.27 1.27)
				)
			)
		)
		(property "Footprint" ""
			(at 196.85 187.96 0)
			(effects
				(font
					(size 1.27 1.27)
				)
				(hide yes)
			)
		)
		(property "Datasheet" ""
			(at 196.85 187.96 0)
			(effects
				(font
					(size 1.27 1.27)
				)
				(hide yes)
			)
		)
		(property "Description" ""
			(at 196.85 187.96 0)
			(effects
				(font
					(size 1.27 1.27)
				)
			)
		)
		(pin "1"
		)
		(instances
			(project "lpddr4-testbed"
				(path ""
					(reference "#PWR0114")
					(unit 1)
				)
			)
		)
	)
	(symbol
		(lib_id "antmicropower:GND")
		(at 226.695 187.96 0)
		(unit 1)
		(exclude_from_sim no)
		(in_bom yes)
		(on_board yes)
		(dnp no)
		(property "Reference" "#PWR0115"
			(at 226.695 194.31 0)
			(effects
				(font
					(size 1.27 1.27)
				)
				(hide yes)
			)
		)
		(property "Value" "GND"
			(at 226.822 192.3542 0)
			(effects
				(font
					(size 1.27 1.27)
				)
			)
		)
		(property "Footprint" ""
			(at 226.695 187.96 0)
			(effects
				(font
					(size 1.27 1.27)
				)
				(hide yes)
			)
		)
		(property "Datasheet" ""
			(at 226.695 187.96 0)
			(effects
				(font
					(size 1.27 1.27)
				)
				(hide yes)
			)
		)
		(property "Description" ""
			(at 226.695 187.96 0)
			(effects
				(font
					(size 1.27 1.27)
				)
			)
		)
		(pin "1"
		)
		(instances
			(project "lpddr4-testbed"
				(path ""
					(reference "#PWR0115")
					(unit 1)
				)
			)
		)
	)
	(symbol
		(lib_id "antmicropower:GND")
		(at 232.41 187.96 0)
		(unit 1)
		(exclude_from_sim no)
		(in_bom yes)
		(on_board yes)
		(dnp no)
		(property "Reference" "#PWR0116"
			(at 232.41 194.31 0)
			(effects
				(font
					(size 1.27 1.27)
				)
				(hide yes)
			)
		)
		(property "Value" "GND"
			(at 232.537 192.3542 0)
			(effects
				(font
					(size 1.27 1.27)
				)
			)
		)
		(property "Footprint" ""
			(at 232.41 187.96 0)
			(effects
				(font
					(size 1.27 1.27)
				)
				(hide yes)
			)
		)
		(property "Datasheet" ""
			(at 232.41 187.96 0)
			(effects
				(font
					(size 1.27 1.27)
				)
				(hide yes)
			)
		)
		(property "Description" ""
			(at 232.41 187.96 0)
			(effects
				(font
					(size 1.27 1.27)
				)
			)
		)
		(pin "1"
		)
		(instances
			(project "lpddr4-testbed"
				(path ""
					(reference "#PWR0116")
					(unit 1)
				)
			)
		)
	)
	(symbol
		(lib_id "antmicroCapacitors0402:C_100n_0402")
		(at 240.665 187.325 90)
		(unit 1)
		(exclude_from_sim no)
		(in_bom yes)
		(on_board yes)
		(dnp no)
		(property "Reference" "C39"
			(at 241.3 182.88 90)
			(effects
				(font
					(size 1.27 1.27)
					(thickness 0.15)
				)
				(justify right)
			)
		)
		(property "Value" "C_100n_0402"
			(at 244.475 187.325 0)
			(effects
				(font
					(size 1.27 1.27)
					(thickness 0.15)
				)
				(justify left bottom)
				(hide yes)
			)
		)
		(property "Footprint" "antmicro-footprints:C_0402_1005Metric"
			(at 235.585 182.245 0)
			(effects
				(font
					(size 1.27 1.27)
					(thickness 0.15)
				)
				(justify left bottom)
				(hide yes)
			)
		)
		(property "Datasheet" ""
			(at 240.665 187.325 0)
			(effects
				(font
					(size 1.27 1.27)
					(thickness 0.15)
				)
				(justify left bottom)
				(hide yes)
			)
		)
		(property "Description" ""
			(at 240.665 187.325 0)
			(effects
				(font
					(size 1.27 1.27)
				)
			)
		)
		(property "Manufacturer" "Walsin"
			(at 230.505 182.245 0)
			(effects
				(font
					(size 1.27 1.27)
					(thickness 0.15)
				)
				(justify left bottom)
				(hide yes)
			)
		)
		(property "MPN" "0402X104K6R3CT"
			(at 233.045 182.245 0)
			(effects
				(font
					(size 1.27 1.27)
					(thickness 0.15)
				)
				(justify left bottom)
				(hide yes)
			)
		)
		(property "Val" "100n"
			(at 241.3 186.69 90)
			(effects
				(font
					(size 1.27 1.27)
					(thickness 0.15)
				)
				(justify right)
			)
		)
		(property "License" "Apache-2.0"
			(at 263.525 167.005 0)
			(effects
				(font
					(size 1.27 1.27)
					(thickness 0.15)
				)
				(justify left bottom)
				(hide yes)
			)
		)
		(property "Author" "Antmicro"
			(at 266.065 167.005 0)
			(effects
				(font
					(size 1.27 1.27)
					(thickness 0.15)
				)
				(justify left bottom)
				(hide yes)
			)
		)
		(property "Voltage" "50V"
			(at 268.605 167.005 0)
			(effects
				(font
					(size 1.27 1.27)
				)
				(justify left bottom)
				(hide yes)
			)
		)
		(property "Dielectric" "X5R"
			(at 271.145 167.005 0)
			(effects
				(font
					(size 1.27 1.27)
				)
				(justify left bottom)
				(hide yes)
			)
		)
		(pin "1"
		)
		(pin "2"
		)
		(instances
			(project "lpddr4-testbed"
				(path ""
					(reference "C39")
					(unit 1)
				)
			)
		)
	)
	(symbol
		(lib_id "antmicropower:GND")
		(at 240.665 187.96 0)
		(unit 1)
		(exclude_from_sim no)
		(in_bom yes)
		(on_board yes)
		(dnp no)
		(property "Reference" "#PWR0117"
			(at 240.665 194.31 0)
			(effects
				(font
					(size 1.27 1.27)
				)
				(hide yes)
			)
		)
		(property "Value" "GND"
			(at 240.792 192.3542 0)
			(effects
				(font
					(size 1.27 1.27)
				)
			)
		)
		(property "Footprint" ""
			(at 240.665 187.96 0)
			(effects
				(font
					(size 1.27 1.27)
				)
				(hide yes)
			)
		)
		(property "Datasheet" ""
			(at 240.665 187.96 0)
			(effects
				(font
					(size 1.27 1.27)
				)
				(hide yes)
			)
		)
		(property "Description" ""
			(at 240.665 187.96 0)
			(effects
				(font
					(size 1.27 1.27)
				)
			)
		)
		(pin "1"
		)
		(instances
			(project "lpddr4-testbed"
				(path ""
					(reference "#PWR0117")
					(unit 1)
				)
			)
		)
	)
	(symbol
		(lib_id "antmicroTestPoints:TP_0.75mm_SMD")
		(at 196.85 186.69 180)
		(unit 1)
		(exclude_from_sim no)
		(in_bom yes)
		(on_board yes)
		(dnp no)
		(property "Reference" "TP3"
			(at 190.5 186.69 0)
			(effects
				(font
					(size 1.27 1.27)
					(thickness 0.15)
				)
			)
		)
		(property "Value" "TP_0.75mm_SMD"
			(at 181.61 179.07 0)
			(effects
				(font
					(size 1.27 1.27)
					(thickness 0.15)
				)
				(justify left bottom)
				(hide yes)
			)
		)
		(property "Footprint" "antmicro-footprints:TP_SMD_0.75mm"
			(at 181.61 176.53 0)
			(effects
				(font
					(size 1.27 1.27)
					(thickness 0.15)
				)
				(justify left bottom)
				(hide yes)
			)
		)
		(property "Datasheet" ""
			(at 181.61 173.99 0)
			(effects
				(font
					(size 1.27 1.27)
					(thickness 0.15)
				)
				(justify left bottom)
				(hide yes)
			)
		)
		(property "Description" ""
			(at 196.85 186.69 0)
			(effects
				(font
					(size 1.27 1.27)
				)
			)
		)
		(property "MPN" ""
			(at 196.85 186.69 0)
			(effects
				(font
					(size 1.27 1.27)
				)
				(hide yes)
			)
		)
		(property "Manufacturer" ""
			(at 196.85 186.69 0)
			(effects
				(font
					(size 1.27 1.27)
				)
				(hide yes)
			)
		)
		(property "Author" "Antmicro"
			(at 181.61 171.45 0)
			(effects
				(font
					(size 1.27 1.27)
					(thickness 0.15)
				)
				(justify left bottom)
				(hide yes)
			)
		)
		(property "License" "Apache-2.0"
			(at 181.61 168.91 0)
			(effects
				(font
					(size 1.27 1.27)
					(thickness 0.15)
				)
				(justify left bottom)
				(hide yes)
			)
		)
		(pin "1"
		)
		(instances
			(project "lpddr4-testbed"
				(path ""
					(reference "TP3")
					(unit 1)
				)
			)
		)
	)
	(symbol
		(lib_id "antmicroLEDIndicationDiscrete:LED_G_0603_KP-1608CGCK")
		(at 266.7 134.62 270)
		(unit 1)
		(exclude_from_sim no)
		(in_bom yes)
		(on_board yes)
		(dnp no)
		(property "Reference" "D3"
			(at 267.97 133.35 0)
			(effects
				(font
					(size 1.27 1.27)
					(thickness 0.15)
				)
				(justify left)
			)
		)
		(property "Value" "LED_G_0603_KP-1608CGCK"
			(at 262.89 129.54 0)
			(effects
				(font
					(size 1.27 1.27)
					(thickness 0.15)
				)
				(justify left)
			)
		)
		(property "Footprint" "antmicro-footprints:LED_0603_1608Metric_G"
			(at 256.54 157.48 0)
			(effects
				(font
					(size 1.27 1.27)
					(thickness 0.15)
				)
				(justify left bottom)
				(hide yes)
			)
		)
		(property "Datasheet" "http://www.farnell.com/datasheets/2045956.pdf"
			(at 254 157.48 0)
			(effects
				(font
					(size 1.27 1.27)
					(thickness 0.15)
				)
				(justify left bottom)
				(hide yes)
			)
		)
		(property "Description" ""
			(at 266.7 134.62 0)
			(effects
				(font
					(size 1.27 1.27)
				)
			)
		)
		(property "MPN" "KP-1608CGCK"
			(at 251.46 157.48 0)
			(effects
				(font
					(size 1.27 1.27)
					(thickness 0.15)
				)
				(justify left bottom)
				(hide yes)
			)
		)
		(property "Manufacturer" "Kingbright"
			(at 248.92 157.48 0)
			(effects
				(font
					(size 1.27 1.27)
					(thickness 0.15)
				)
				(justify left bottom)
				(hide yes)
			)
		)
		(property "Author" "Antmicro"
			(at 246.38 157.48 0)
			(effects
				(font
					(size 1.27 1.27)
					(thickness 0.15)
				)
				(justify left bottom)
				(hide yes)
			)
		)
		(property "License" "Apache-2.0"
			(at 243.84 157.48 0)
			(effects
				(font
					(size 1.27 1.27)
					(thickness 0.15)
				)
				(justify left bottom)
				(hide yes)
			)
		)
		(pin "1"
		)
		(pin "2"
		)
		(instances
			(project "lpddr4-testbed"
				(path ""
					(reference "D3")
					(unit 1)
				)
			)
		)
	)
	(symbol
		(lib_name "TP_0.75mm_SMD_1")
		(lib_id "antmicroTestPoints:TP_0.75mm_SMD")
		(at 241.3 133.35 0)
		(unit 1)
		(exclude_from_sim no)
		(in_bom yes)
		(on_board yes)
		(dnp no)
		(property "Reference" "TP1"
			(at 247.65 133.35 0)
			(effects
				(font
					(size 1.27 1.27)
					(thickness 0.15)
				)
			)
		)
		(property "Value" "TP_0.75mm_SMD"
			(at 256.54 140.97 0)
			(effects
				(font
					(size 1.27 1.27)
					(thickness 0.15)
				)
				(justify left bottom)
				(hide yes)
			)
		)
		(property "Footprint" "antmicro-footprints:TP_SMD_0.75mm"
			(at 256.54 143.51 0)
			(effects
				(font
					(size 1.27 1.27)
					(thickness 0.15)
				)
				(justify left bottom)
				(hide yes)
			)
		)
		(property "Datasheet" ""
			(at 256.54 146.05 0)
			(effects
				(font
					(size 1.27 1.27)
					(thickness 0.15)
				)
				(justify left bottom)
				(hide yes)
			)
		)
		(property "Description" ""
			(at 241.3 133.35 0)
			(effects
				(font
					(size 1.27 1.27)
				)
			)
		)
		(property "MPN" ""
			(at 241.3 133.35 0)
			(effects
				(font
					(size 1.27 1.27)
				)
				(hide yes)
			)
		)
		(property "Manufacturer" ""
			(at 241.3 133.35 0)
			(effects
				(font
					(size 1.27 1.27)
				)
				(hide yes)
			)
		)
		(property "Author" "Antmicro"
			(at 256.54 148.59 0)
			(effects
				(font
					(size 1.27 1.27)
					(thickness 0.15)
				)
				(justify left bottom)
				(hide yes)
			)
		)
		(property "License" "Apache-2.0"
			(at 256.54 151.13 0)
			(effects
				(font
					(size 1.27 1.27)
					(thickness 0.15)
				)
				(justify left bottom)
				(hide yes)
			)
		)
		(pin "1"
		)
		(instances
			(project "lpddr4-testbed"
				(path ""
					(reference "TP1")
					(unit 1)
				)
			)
		)
	)
	(symbol
		(lib_id "antmicropower:PWR_FLAG")
		(at 229.235 74.295 0)
		(unit 1)
		(exclude_from_sim no)
		(in_bom yes)
		(on_board yes)
		(dnp no)
		(property "Reference" "#FLG0105"
			(at 229.235 72.39 0)
			(effects
				(font
					(size 1.27 1.27)
				)
				(hide yes)
			)
		)
		(property "Value" "PWR_FLAG"
			(at 229.235 70.485 0)
			(effects
				(font
					(size 1.27 1.27)
				)
			)
		)
		(property "Footprint" ""
			(at 229.235 74.295 0)
			(effects
				(font
					(size 1.27 1.27)
				)
				(hide yes)
			)
		)
		(property "Datasheet" ""
			(at 229.235 74.295 0)
			(effects
				(font
					(size 1.27 1.27)
				)
				(hide yes)
			)
		)
		(property "Description" ""
			(at 229.235 74.295 0)
			(effects
				(font
					(size 1.27 1.27)
				)
			)
		)
		(pin "1"
		)
		(instances
			(project "lpddr4-testbed"
				(path ""
					(reference "#FLG0105")
					(unit 1)
				)
			)
		)
	)
	(symbol
		(lib_id "antmicroInterfaceIOExpanders:PCA6408A_TSSOP")
		(at 210.82 120.65 0)
		(unit 1)
		(exclude_from_sim no)
		(in_bom yes)
		(on_board yes)
		(dnp no)
		(fields_autoplaced yes)
		(property "Reference" "IC1"
			(at 221.615 113.03 0)
			(effects
				(font
					(size 1.27 1.27)
					(thickness 0.15)
				)
			)
		)
		(property "Value" "PCA6408A_TSSOP"
			(at 221.615 115.57 0)
			(effects
				(font
					(size 1.27 1.27)
					(thickness 0.15)
				)
			)
		)
		(property "Footprint" "antmicro-footprints:TSSOP-16_4.4x5mm_P0.65mm"
			(at 246.38 128.27 0)
			(effects
				(font
					(size 1.27 1.27)
					(thickness 0.15)
				)
				(justify left bottom)
				(hide yes)
			)
		)
		(property "Datasheet" "https://www.mouser.pl/datasheet/2/302/PCA6408A-1127604.pdf"
			(at 246.38 130.81 0)
			(effects
				(font
					(size 1.27 1.27)
					(thickness 0.15)
				)
				(justify left bottom)
				(hide yes)
			)
		)
		(property "Description" ""
			(at 210.82 120.65 0)
			(effects
				(font
					(size 1.27 1.27)
				)
			)
		)
		(property "Manufacturer" "NXP"
			(at 246.38 133.35 0)
			(effects
				(font
					(size 1.27 1.27)
					(thickness 0.15)
				)
				(justify left bottom)
				(hide yes)
			)
		)
		(property "MPN" "PCA6408APW"
			(at 246.38 135.89 0)
			(effects
				(font
					(size 1.27 1.27)
					(thickness 0.15)
				)
				(justify left bottom)
				(hide yes)
			)
		)
		(property "Author" "Antmicro"
			(at 246.38 138.43 0)
			(effects
				(font
					(size 1.27 1.27)
					(thickness 0.15)
				)
				(justify left bottom)
				(hide yes)
			)
		)
		(property "License" "Apache-2.0"
			(at 246.38 140.97 0)
			(effects
				(font
					(size 1.27 1.27)
					(thickness 0.15)
				)
				(justify left bottom)
				(hide yes)
			)
		)
		(pin "1"
		)
		(pin "10"
		)
		(pin "11"
		)
		(pin "12"
		)
		(pin "13"
		)
		(pin "14"
		)
		(pin "15"
		)
		(pin "16"
		)
		(pin "2"
		)
		(pin "3"
		)
		(pin "4"
		)
		(pin "5"
		)
		(pin "6"
		)
		(pin "7"
		)
		(pin "8"
		)
		(pin "9"
		)
		(instances
			(project "lpddr4-testbed"
				(path ""
					(reference "IC1")
					(unit 1)
				)
			)
		)
	)
	(symbol
		(lib_id "antmicroLEDIndicationDiscrete:LED_G_0603_KP-1608CGCK")
		(at 259.08 134.62 270)
		(unit 1)
		(exclude_from_sim no)
		(in_bom yes)
		(on_board yes)
		(dnp no)
		(property "Reference" "D4"
			(at 260.35 133.35 0)
			(effects
				(font
					(size 1.27 1.27)
					(thickness 0.15)
				)
				(justify left)
			)
		)
		(property "Value" "LED_G_0603_KP-1608CGCK"
			(at 256.54 129.54 0)
			(effects
				(font
					(size 1.27 1.27)
					(thickness 0.15)
				)
				(justify left)
			)
		)
		(property "Footprint" "antmicro-footprints:LED_0603_1608Metric_G"
			(at 248.92 157.48 0)
			(effects
				(font
					(size 1.27 1.27)
					(thickness 0.15)
				)
				(justify left bottom)
				(hide yes)
			)
		)
		(property "Datasheet" "http://www.farnell.com/datasheets/2045956.pdf"
			(at 246.38 157.48 0)
			(effects
				(font
					(size 1.27 1.27)
					(thickness 0.15)
				)
				(justify left bottom)
				(hide yes)
			)
		)
		(property "Description" ""
			(at 259.08 134.62 0)
			(effects
				(font
					(size 1.27 1.27)
				)
			)
		)
		(property "MPN" "KP-1608CGCK"
			(at 243.84 157.48 0)
			(effects
				(font
					(size 1.27 1.27)
					(thickness 0.15)
				)
				(justify left bottom)
				(hide yes)
			)
		)
		(property "Manufacturer" "Kingbright"
			(at 241.3 157.48 0)
			(effects
				(font
					(size 1.27 1.27)
					(thickness 0.15)
				)
				(justify left bottom)
				(hide yes)
			)
		)
		(property "Author" "Antmicro"
			(at 238.76 157.48 0)
			(effects
				(font
					(size 1.27 1.27)
					(thickness 0.15)
				)
				(justify left bottom)
				(hide yes)
			)
		)
		(property "License" "Apache-2.0"
			(at 236.22 157.48 0)
			(effects
				(font
					(size 1.27 1.27)
					(thickness 0.15)
				)
				(justify left bottom)
				(hide yes)
			)
		)
		(pin "1"
		)
		(pin "2"
		)
		(instances
			(project "lpddr4-testbed"
				(path ""
					(reference "D4")
					(unit 1)
				)
			)
		)
	)
	(symbol
		(lib_id "antmicroMemory:AT24CS01_SOT23")
		(at 205.74 181.61 0)
		(unit 1)
		(exclude_from_sim no)
		(in_bom yes)
		(on_board yes)
		(dnp no)
		(fields_autoplaced yes)
		(property "Reference" "IC2"
			(at 215.9 173.99 0)
			(effects
				(font
					(size 1.27 1.27)
					(thickness 0.15)
				)
			)
		)
		(property "Value" "AT24CS01_SOT23"
			(at 215.9 176.53 0)
			(effects
				(font
					(size 1.27 1.27)
					(thickness 0.15)
				)
			)
		)
		(property "Footprint" "antmicro-footprints:SOT-23-5"
			(at 241.3 189.23 0)
			(effects
				(font
					(size 1.27 1.27)
					(thickness 0.15)
				)
				(justify left bottom)
				(hide yes)
			)
		)
		(property "Datasheet" "http://ww1.microchip.com/downloads/en/devicedoc/Atmel-8815-SEEPROM-AT24CS01-02-Datasheet.pdf"
			(at 241.3 191.77 0)
			(effects
				(font
					(size 1.27 1.27)
					(thickness 0.15)
				)
				(justify left bottom)
				(hide yes)
			)
		)
		(property "Description" ""
			(at 205.74 181.61 0)
			(effects
				(font
					(size 1.27 1.27)
				)
			)
		)
		(property "Manufacturer" "Atmel"
			(at 241.3 194.31 0)
			(effects
				(font
					(size 1.27 1.27)
					(thickness 0.15)
				)
				(justify left bottom)
				(hide yes)
			)
		)
		(property "MPN" "AT24CS01-ST"
			(at 241.3 196.85 0)
			(effects
				(font
					(size 1.27 1.27)
					(thickness 0.15)
				)
				(justify left bottom)
				(hide yes)
			)
		)
		(property "Author" "Antmicro"
			(at 241.3 199.39 0)
			(effects
				(font
					(size 1.27 1.27)
					(thickness 0.15)
				)
				(justify left bottom)
				(hide yes)
			)
		)
		(property "License" "Apache-2.0"
			(at 241.3 201.93 0)
			(effects
				(font
					(size 1.27 1.27)
					(thickness 0.15)
				)
				(justify left bottom)
				(hide yes)
			)
		)
		(pin "1"
		)
		(pin "2"
		)
		(pin "3"
		)
		(pin "4"
		)
		(pin "5"
		)
		(instances
			(project "lpddr4-testbed"
				(path ""
					(reference "IC2")
					(unit 1)
				)
			)
		)
	)
	(symbol
		(lib_id "antmicroFixedInductors:L_2u2_1.5A_0806")
		(at 197.485 86.36 0)
		(unit 1)
		(exclude_from_sim no)
		(in_bom yes)
		(on_board yes)
		(dnp no)
		(fields_autoplaced yes)
		(property "Reference" "L1"
			(at 200.025 81.28 0)
			(effects
				(font
					(size 1.27 1.27)
					(thickness 0.15)
				)
			)
		)
		(property "Value" "L_2u2_1.5A_1285AS-H"
			(at 211.455 88.9 0)
			(effects
				(font
					(size 1.27 1.27)
					(thickness 0.15)
				)
				(justify left bottom)
				(hide yes)
			)
		)
		(property "Footprint" "antmicro-footprints:L_0806_2016Metric"
			(at 211.455 93.98 0)
			(effects
				(font
					(size 1.27 1.27)
					(thickness 0.15)
				)
				(justify left bottom)
				(hide yes)
			)
		)
		(property "Datasheet" "https://search.murata.co.jp/Ceramy/image/img/P02/J(E)TE243A-0011.pdf"
			(at 211.455 96.52 0)
			(effects
				(font
					(size 1.27 1.27)
					(thickness 0.15)
				)
				(justify left bottom)
				(hide yes)
			)
		)
		(property "Description" ""
			(at 197.485 86.36 0)
			(effects
				(font
					(size 1.27 1.27)
				)
			)
		)
		(property "Val" "2u2/1.5A"
			(at 200.025 83.82 0)
			(effects
				(font
					(size 1.27 1.27)
				)
			)
		)
		(property "Manufacturer" "Murata"
			(at 211.455 99.06 0)
			(effects
				(font
					(size 1.27 1.27)
				)
				(justify left bottom)
				(hide yes)
			)
		)
		(property "MPN" "1285AS-H-2R2M=P2"
			(at 211.455 101.6 0)
			(effects
				(font
					(size 1.27 1.27)
				)
				(justify left bottom)
				(hide yes)
			)
		)
		(property "ISat" ""
			(at 211.455 102.87 0)
			(effects
				(font
					(size 1.27 1.27)
				)
				(justify left)
				(hide yes)
			)
		)
		(property "Isat" "1.2A"
			(at 211.455 104.14 0)
			(effects
				(font
					(size 1.27 1.27)
				)
				(justify left bottom)
				(hide yes)
			)
		)
		(property "IMax" ""
			(at 211.455 106.68 0)
			(effects
				(font
					(size 1.27 1.27)
					(thickness 0.15)
				)
				(justify left bottom)
				(hide yes)
			)
		)
		(property "Imax" "1.5A"
			(at 211.455 106.68 0)
			(effects
				(font
					(size 1.27 1.27)
				)
				(justify left bottom)
				(hide yes)
			)
		)
		(property "Size" "0806_2016Metric"
			(at 211.455 109.22 0)
			(effects
				(font
					(size 1.27 1.27)
				)
				(justify left bottom)
				(hide yes)
			)
		)
		(property "Author" "Antmicro"
			(at 211.455 111.76 0)
			(effects
				(font
					(size 1.27 1.27)
				)
				(justify left bottom)
				(hide yes)
			)
		)
		(property "License" "Apache-2.0"
			(at 211.455 114.3 0)
			(effects
				(font
					(size 1.27 1.27)
				)
				(justify left bottom)
				(hide yes)
			)
		)
		(pin "1"
		)
		(pin "2"
		)
		(instances
			(project "lpddr4-testbed"
				(path ""
					(reference "L1")
					(unit 1)
				)
			)
		)
	)
	(symbol
		(lib_id "antmicroDCDCConverters:TPS613221A_SOT-23-5")
		(at 210.82 86.36 0)
		(unit 1)
		(exclude_from_sim no)
		(in_bom yes)
		(on_board yes)
		(dnp no)
		(fields_autoplaced yes)
		(property "Reference" "U2"
			(at 218.44 78.74 0)
			(effects
				(font
					(size 1.27 1.27)
					(thickness 0.15)
				)
			)
		)
		(property "Value" "TPS613221A_SOT-23-5"
			(at 218.44 81.28 0)
			(effects
				(font
					(size 1.27 1.27)
					(thickness 0.15)
				)
			)
		)
		(property "Footprint" "antmicro-footprints:SOT-23-5"
			(at 243.84 93.98 0)
			(effects
				(font
					(size 1.27 1.27)
					(thickness 0.15)
				)
				(justify left bottom)
				(hide yes)
			)
		)
		(property "Datasheet" "https://www.ti.com/lit/ds/symlink/tps61322.pdf?ts=1679307661323&ref_url=https%253A%252F%252Fwww.ti.com%252Fproduct%252FTPS61322%252Fpart-details%252FTPS613221ADBVT%253Futm_source%253Dgoogle%2526utm_medium%253Dcpc%2526utm_campaign%253Docb-tistore-promo-app_opn_en-cpc-storeic-google-wwe%2526utm_content%253DDevice%2526ds_k%253DTPS613221ADBVT%2526DCM%253Dyes%2526gclid%253DCjwKCAjwiOCgBhAgEiwAjv5whAbq73RvnAdgvLpW8LFuSFEla1kNqoJei2y0mTqS4-Xlc-1KWPDvLxoCIUoQAvD_BwE%2526gclsrc%253Daw.ds"
			(at 243.84 96.52 0)
			(effects
				(font
					(size 1.27 1.27)
					(thickness 0.15)
				)
				(justify left bottom)
				(hide yes)
			)
		)
		(property "Description" ""
			(at 210.82 86.36 0)
			(effects
				(font
					(size 1.27 1.27)
				)
			)
		)
		(property "Manufacturer" "Texas Instruments"
			(at 243.84 99.06 0)
			(effects
				(font
					(size 1.27 1.27)
					(thickness 0.15)
				)
				(justify left bottom)
				(hide yes)
			)
		)
		(property "MPN" "TPS613221ADBVT"
			(at 243.84 101.6 0)
			(effects
				(font
					(size 1.27 1.27)
					(thickness 0.15)
				)
				(justify left bottom)
				(hide yes)
			)
		)
		(property "Author" "Antmicro"
			(at 243.84 104.14 0)
			(effects
				(font
					(size 1.27 1.27)
					(thickness 0.15)
				)
				(justify left bottom)
				(hide yes)
			)
		)
		(property "License" "Apache-2.0"
			(at 243.84 106.68 0)
			(effects
				(font
					(size 1.27 1.27)
					(thickness 0.15)
				)
				(justify left bottom)
				(hide yes)
			)
		)
		(pin "1"
		)
		(pin "2"
		)
		(pin "3"
		)
		(pin "4"
		)
		(pin "5"
		)
		(instances
			(project "lpddr4-testbed"
				(path ""
					(reference "U2")
					(unit 1)
				)
			)
		)
	)
	(symbol
		(lib_id "antmicroLEDIndicationDiscrete:LED_G_0603_KP-1608CGCK")
		(at 274.32 134.62 270)
		(unit 1)
		(exclude_from_sim no)
		(in_bom yes)
		(on_board yes)
		(dnp no)
		(property "Reference" "D2"
			(at 275.59 133.35 0)
			(effects
				(font
					(size 1.27 1.27)
					(thickness 0.15)
				)
				(justify left)
			)
		)
		(property "Value" "LED_G_0603_KP-1608CGCK"
			(at 270.51 129.54 0)
			(effects
				(font
					(size 1.27 1.27)
					(thickness 0.15)
				)
				(justify left)
			)
		)
		(property "Footprint" "antmicro-footprints:LED_0603_1608Metric_G"
			(at 264.16 157.48 0)
			(effects
				(font
					(size 1.27 1.27)
					(thickness 0.15)
				)
				(justify left bottom)
				(hide yes)
			)
		)
		(property "Datasheet" "http://www.farnell.com/datasheets/2045956.pdf"
			(at 261.62 157.48 0)
			(effects
				(font
					(size 1.27 1.27)
					(thickness 0.15)
				)
				(justify left bottom)
				(hide yes)
			)
		)
		(property "Description" ""
			(at 274.32 134.62 0)
			(effects
				(font
					(size 1.27 1.27)
				)
			)
		)
		(property "MPN" "KP-1608CGCK"
			(at 259.08 157.48 0)
			(effects
				(font
					(size 1.27 1.27)
					(thickness 0.15)
				)
				(justify left bottom)
				(hide yes)
			)
		)
		(property "Manufacturer" "Kingbright"
			(at 256.54 157.48 0)
			(effects
				(font
					(size 1.27 1.27)
					(thickness 0.15)
				)
				(justify left bottom)
				(hide yes)
			)
		)
		(property "Author" "Antmicro"
			(at 254 157.48 0)
			(effects
				(font
					(size 1.27 1.27)
					(thickness 0.15)
				)
				(justify left bottom)
				(hide yes)
			)
		)
		(property "License" "Apache-2.0"
			(at 251.46 157.48 0)
			(effects
				(font
					(size 1.27 1.27)
					(thickness 0.15)
				)
				(justify left bottom)
				(hide yes)
			)
		)
		(pin "1"
		)
		(pin "2"
		)
		(instances
			(project "lpddr4-testbed"
				(path ""
					(reference "D2")
					(unit 1)
				)
			)
		)
	)
	(symbol
		(lib_name "TP_0.75mm_SMD_2")
		(lib_id "antmicroTestPoints:TP_0.75mm_SMD")
		(at 241.3 135.89 0)
		(unit 1)
		(exclude_from_sim no)
		(in_bom yes)
		(on_board yes)
		(dnp no)
		(property "Reference" "TP2"
			(at 247.65 135.89 0)
			(effects
				(font
					(size 1.27 1.27)
					(thickness 0.15)
				)
			)
		)
		(property "Value" "TP_0.75mm_SMD"
			(at 256.54 143.51 0)
			(effects
				(font
					(size 1.27 1.27)
					(thickness 0.15)
				)
				(justify left bottom)
				(hide yes)
			)
		)
		(property "Footprint" "antmicro-footprints:TP_SMD_0.75mm"
			(at 256.54 146.05 0)
			(effects
				(font
					(size 1.27 1.27)
					(thickness 0.15)
				)
				(justify left bottom)
				(hide yes)
			)
		)
		(property "Datasheet" ""
			(at 256.54 148.59 0)
			(effects
				(font
					(size 1.27 1.27)
					(thickness 0.15)
				)
				(justify left bottom)
				(hide yes)
			)
		)
		(property "Description" ""
			(at 241.3 135.89 0)
			(effects
				(font
					(size 1.27 1.27)
				)
			)
		)
		(property "MPN" ""
			(at 241.3 135.89 0)
			(effects
				(font
					(size 1.27 1.27)
				)
				(hide yes)
			)
		)
		(property "Manufacturer" ""
			(at 241.3 135.89 0)
			(effects
				(font
					(size 1.27 1.27)
				)
				(hide yes)
			)
		)
		(property "Author" "Antmicro"
			(at 256.54 151.13 0)
			(effects
				(font
					(size 1.27 1.27)
					(thickness 0.15)
				)
				(justify left bottom)
				(hide yes)
			)
		)
		(property "License" "Apache-2.0"
			(at 256.54 153.67 0)
			(effects
				(font
					(size 1.27 1.27)
					(thickness 0.15)
				)
				(justify left bottom)
				(hide yes)
			)
		)
		(pin "1"
		)
		(instances
			(project "lpddr4-testbed"
				(path ""
					(reference "TP2")
					(unit 1)
				)
			)
		)
	)
	(symbol
		(lib_id "antmicroLEDIndicationDiscrete:LED_G_0603_KP-1608CGCK")
		(at 281.94 134.62 270)
		(unit 1)
		(exclude_from_sim no)
		(in_bom yes)
		(on_board yes)
		(dnp no)
		(property "Reference" "D1"
			(at 283.21 133.35 0)
			(effects
				(font
					(size 1.27 1.27)
					(thickness 0.15)
				)
				(justify left)
			)
		)
		(property "Value" "LED_G_0603_KP-1608CGCK"
			(at 278.13 129.54 0)
			(effects
				(font
					(size 1.27 1.27)
					(thickness 0.15)
				)
				(justify left)
			)
		)
		(property "Footprint" "antmicro-footprints:LED_0603_1608Metric_G"
			(at 271.78 157.48 0)
			(effects
				(font
					(size 1.27 1.27)
					(thickness 0.15)
				)
				(justify left bottom)
				(hide yes)
			)
		)
		(property "Datasheet" "http://www.farnell.com/datasheets/2045956.pdf"
			(at 269.24 157.48 0)
			(effects
				(font
					(size 1.27 1.27)
					(thickness 0.15)
				)
				(justify left bottom)
				(hide yes)
			)
		)
		(property "Description" ""
			(at 281.94 134.62 0)
			(effects
				(font
					(size 1.27 1.27)
				)
			)
		)
		(property "MPN" "KP-1608CGCK"
			(at 266.7 157.48 0)
			(effects
				(font
					(size 1.27 1.27)
					(thickness 0.15)
				)
				(justify left bottom)
				(hide yes)
			)
		)
		(property "Manufacturer" "Kingbright"
			(at 264.16 157.48 0)
			(effects
				(font
					(size 1.27 1.27)
					(thickness 0.15)
				)
				(justify left bottom)
				(hide yes)
			)
		)
		(property "Author" "Antmicro"
			(at 261.62 157.48 0)
			(effects
				(font
					(size 1.27 1.27)
					(thickness 0.15)
				)
				(justify left bottom)
				(hide yes)
			)
		)
		(property "License" "Apache-2.0"
			(at 259.08 157.48 0)
			(effects
				(font
					(size 1.27 1.27)
					(thickness 0.15)
				)
				(justify left bottom)
				(hide yes)
			)
		)
		(pin "1"
		)
		(pin "2"
		)
		(instances
			(project "lpddr4-testbed"
				(path ""
					(reference "D1")
					(unit 1)
				)
			)
		)
	)
	(symbol
		(lib_id "antmicropower:PWR_FLAG")
		(at 207.645 86.995 180)
		(unit 1)
		(exclude_from_sim no)
		(in_bom yes)
		(on_board yes)
		(dnp no)
		(property "Reference" "#FLG0106"
			(at 207.645 88.9 0)
			(effects
				(font
					(size 1.27 1.27)
				)
				(hide yes)
			)
		)
		(property "Value" "PWR_FLAG"
			(at 207.645 90.805 0)
			(effects
				(font
					(size 1.27 1.27)
				)
			)
		)
		(property "Footprint" ""
			(at 207.645 86.995 0)
			(effects
				(font
					(size 1.27 1.27)
				)
				(hide yes)
			)
		)
		(property "Datasheet" ""
			(at 207.645 86.995 0)
			(effects
				(font
					(size 1.27 1.27)
				)
				(hide yes)
			)
		)
		(property "Description" ""
			(at 207.645 86.995 0)
			(effects
				(font
					(size 1.27 1.27)
				)
			)
		)
		(pin "1"
		)
		(instances
			(project "lpddr4-testbed"
				(path ""
					(reference "#FLG0106")
					(unit 1)
				)
			)
		)
	)
)
